(kicad_pcb
	(version 20260206)
	(generator "pcbnew")
	(generator_version "10.0")
	(general
		(thickness 1.6)
		(legacy_teardrops no)
	)
	(paper "A4")
	(title_block
		(title "04192023_DAF0TMB3IC0_F0TG_MB_C_brd_V02_OCP.brd")
		(comment 1 "Grand Teton / footprint 1456 of 8354 (J29), pads 114-226 of 291")
	)
	(layers
		(0 "F.Cu" signal "TOP")
		(4 "In1.Cu" signal "GND")
		(6 "In2.Cu" signal "IN1")
		(8 "In3.Cu" signal "GND1")
		(10 "In4.Cu" signal "IN2")
		(12 "In5.Cu" signal "GND2")
		(14 "In6.Cu" signal "IN3")
		(16 "In7.Cu" signal "GND3")
		(18 "In8.Cu" signal "VCC")
		(20 "In9.Cu" signal "VCC1")
		(22 "In10.Cu" signal "GND4")
		(24 "In11.Cu" signal "IN4")
		(26 "In12.Cu" signal "GND5")
		(28 "In13.Cu" signal "IN5")
		(30 "In14.Cu" signal "GND6")
		(32 "In15.Cu" signal "IN6")
		(34 "In16.Cu" signal "GND7")
		(2 "B.Cu" signal "BOTTOM")
		(9 "F.Adhes" user "F.Adhesive")
		(11 "B.Adhes" user "B.Adhesive")
		(13 "F.Paste" user "Package Geometry/Pastemask Top")
		(15 "B.Paste" user "Package Geometry/Pastemask Bottom")
		(5 "F.SilkS" user "Ref Des/Silkscreen Top")
		(7 "B.SilkS" user "Ref Des/Silkscreen Bottom")
		(1 "F.Mask" user "Board Geometry/Soldermask Top")
		(3 "B.Mask" user "Board Geometry/Soldermask Bottom")
		(17 "Dwgs.User" user "User.Drawings")
		(19 "Cmts.User" user "User.Comments")
		(21 "Eco1.User" user "User.Eco1")
		(23 "Eco2.User" user "User.Eco2")
		(25 "Edge.Cuts" user "Board Geometry/Outline")
		(27 "Margin" user)
		(31 "F.CrtYd" user "Package Geometry/Place Bound Top")
		(29 "B.CrtYd" user "Package Geometry/Place Bound Bottom")
		(35 "F.Fab" user "Ref Des/Assembly Top")
		(33 "B.Fab" user "Ref Des/Assembly Bottom")
	)
	(footprint ""
		(layer "F.Cu")
		(at 189.110112 -255.560322 180)
		(property "Reference" "J29"
			(at -2.7178 -81.857088 0)
			(unlocked yes)
			(layer "F.SilkS")
			(effects
				(font
					(size 0.7874 0.5842)
					(thickness 0.1524)
				)
			)
		)
		(property "Value" ""
			(at 0 0 180)
			(layer "F.Fab")
			(effects
				(font
					(size 1.27 1.27)
				)
			)
		)
		(duplicate_pad_numbers_are_jumpers no)
		(pad "114" smd rect
			(at -2.050034 37.824918 90)
			(size 0.519938 1.4986)
			(layers "F.Cu" "F.Mask" "F.Paste")
			(net "GND")
		)
		(pad "115" smd rect
			(at -2.050034 38.675056 90)
			(size 0.519938 1.4986)
			(layers "F.Cu" "F.Mask" "F.Paste")
			(net "M_J_CPU1_SB_DQS_DP<1>")
		)
		(pad "116" smd rect
			(at -2.050034 39.52494 90)
			(size 0.519938 1.4986)
			(layers "F.Cu" "F.Mask" "F.Paste")
			(net "M_J_CPU1_SB_DQS_DN<1>")
		)
		(pad "117" smd rect
			(at -2.050034 40.375078 90)
			(size 0.519938 1.4986)
			(layers "F.Cu" "F.Mask" "F.Paste")
			(net "GND")
		)
		(pad "118" smd rect
			(at -2.050034 41.224962 90)
			(size 0.519938 1.4986)
			(layers "F.Cu" "F.Mask" "F.Paste")
			(net "M_J_CPU1_SB_DQ<12>")
		)
		(pad "119" smd rect
			(at -2.050034 42.0751 90)
			(size 0.519938 1.4986)
			(layers "F.Cu" "F.Mask" "F.Paste")
			(net "GND")
		)
		(pad "120" smd rect
			(at -2.050034 42.924984 90)
			(size 0.519938 1.4986)
			(layers "F.Cu" "F.Mask" "F.Paste")
			(net "M_J_CPU1_SB_DQ<13>")
		)
		(pad "121" smd rect
			(at -2.050034 43.775122 90)
			(size 0.519938 1.4986)
			(layers "F.Cu" "F.Mask" "F.Paste")
			(net "GND")
		)
		(pad "122" smd rect
			(at -2.050034 44.625006 90)
			(size 0.519938 1.4986)
			(layers "F.Cu" "F.Mask" "F.Paste")
			(net "M_J_CPU1_SB_DQ<16>")
		)
		(pad "123" smd rect
			(at -2.050034 45.47489 90)
			(size 0.519938 1.4986)
			(layers "F.Cu" "F.Mask" "F.Paste")
			(net "GND")
		)
		(pad "124" smd rect
			(at -2.050034 46.325028 90)
			(size 0.519938 1.4986)
			(layers "F.Cu" "F.Mask" "F.Paste")
			(net "M_J_CPU1_SB_DQ<17>")
		)
		(pad "125" smd rect
			(at -2.050034 47.174912 90)
			(size 0.519938 1.4986)
			(layers "F.Cu" "F.Mask" "F.Paste")
			(net "GND")
		)
		(pad "126" smd rect
			(at -2.050034 48.02505 90)
			(size 0.519938 1.4986)
			(layers "F.Cu" "F.Mask" "F.Paste")
			(net "M_J_CPU1_SB_DQS_DP<2>")
		)
		(pad "127" smd rect
			(at -2.050034 48.874934 90)
			(size 0.519938 1.4986)
			(layers "F.Cu" "F.Mask" "F.Paste")
			(net "M_J_CPU1_SB_DQS_DN<2>")
		)
		(pad "128" smd rect
			(at -2.050034 49.725072 90)
			(size 0.519938 1.4986)
			(layers "F.Cu" "F.Mask" "F.Paste")
			(net "GND")
		)
		(pad "129" smd rect
			(at -2.050034 50.574956 90)
			(size 0.519938 1.4986)
			(layers "F.Cu" "F.Mask" "F.Paste")
			(net "M_J_CPU1_SB_DQ<20>")
		)
		(pad "130" smd rect
			(at -2.050034 51.425094 90)
			(size 0.519938 1.4986)
			(layers "F.Cu" "F.Mask" "F.Paste")
			(net "GND")
		)
		(pad "131" smd rect
			(at -2.050034 52.274978 90)
			(size 0.519938 1.4986)
			(layers "F.Cu" "F.Mask" "F.Paste")
			(net "M_J_CPU1_SB_DQ<21>")
		)
		(pad "132" smd rect
			(at -2.050034 53.125116 90)
			(size 0.519938 1.4986)
			(layers "F.Cu" "F.Mask" "F.Paste")
			(net "GND")
		)
		(pad "133" smd rect
			(at -2.050034 53.975 90)
			(size 0.519938 1.4986)
			(layers "F.Cu" "F.Mask" "F.Paste")
			(net "M_J_CPU1_SB_DQ<24>")
		)
		(pad "134" smd rect
			(at -2.050034 54.824884 90)
			(size 0.519938 1.4986)
			(layers "F.Cu" "F.Mask" "F.Paste")
			(net "GND")
		)
		(pad "135" smd rect
			(at -2.050034 55.675022 90)
			(size 0.519938 1.4986)
			(layers "F.Cu" "F.Mask" "F.Paste")
			(net "M_J_CPU1_SB_DQ<25>")
		)
		(pad "136" smd rect
			(at -2.050034 56.524906 90)
			(size 0.519938 1.4986)
			(layers "F.Cu" "F.Mask" "F.Paste")
			(net "GND")
		)
		(pad "137" smd rect
			(at -2.050034 57.375044 90)
			(size 0.519938 1.4986)
			(layers "F.Cu" "F.Mask" "F.Paste")
			(net "M_J_CPU1_SB_DQS_DP<3>")
		)
		(pad "138" smd rect
			(at -2.050034 58.224928 90)
			(size 0.519938 1.4986)
			(layers "F.Cu" "F.Mask" "F.Paste")
			(net "M_J_CPU1_SB_DQS_DN<3>")
		)
		(pad "139" smd rect
			(at -2.050034 59.075066 90)
			(size 0.519938 1.4986)
			(layers "F.Cu" "F.Mask" "F.Paste")
			(net "GND")
		)
		(pad "140" smd rect
			(at -2.050034 59.92495 90)
			(size 0.519938 1.4986)
			(layers "F.Cu" "F.Mask" "F.Paste")
			(net "M_J_CPU1_SB_DQ<28>")
		)
		(pad "141" smd rect
			(at -2.050034 60.775088 90)
			(size 0.519938 1.4986)
			(layers "F.Cu" "F.Mask" "F.Paste")
			(net "GND")
		)
		(pad "142" smd rect
			(at -2.050034 61.624972 90)
			(size 0.519938 1.4986)
			(layers "F.Cu" "F.Mask" "F.Paste")
			(net "M_J_CPU1_SB_DQ<29>")
		)
		(pad "143" smd rect
			(at -2.050034 62.47511 90)
			(size 0.519938 1.4986)
			(layers "F.Cu" "F.Mask" "F.Paste")
			(net "GND")
		)
		(pad "144" smd rect
			(at -2.050034 63.324994 90)
			(size 0.519938 1.4986)
			(layers "F.Cu" "F.Mask" "F.Paste")
			(net "Net_2383")
		)
		(pad "145" smd rect
			(at 2.050034 -63.324994 90)
			(size 0.519938 1.4986)
			(layers "F.Cu" "F.Mask" "F.Paste")
			(net "P12V_MEM_CPU1")
		)
		(pad "146" smd rect
			(at 2.050034 -62.47511 90)
			(size 0.519938 1.4986)
			(layers "F.Cu" "F.Mask" "F.Paste")
			(net "P12V_MEM_CPU1")
		)
		(pad "147" smd rect
			(at 2.050034 -61.624972 90)
			(size 0.519938 1.4986)
			(layers "F.Cu" "F.Mask" "F.Paste")
			(net "PWRGD_CHJ_CPU1_DIMM")
		)
		(pad "148" smd rect
			(at 2.050034 -60.775088 90)
			(size 0.519938 1.4986)
			(layers "F.Cu" "F.Mask" "F.Paste")
			(net "PD_CHJ_CPU1_DIMM_SAA")
		)
		(pad "149" smd rect
			(at 2.050034 -59.92495 90)
			(size 0.519938 1.4986)
			(layers "F.Cu" "F.Mask" "F.Paste")
			(net "Net_2384")
		)
		(pad "150" smd rect
			(at 2.050034 -59.075066 90)
			(size 0.519938 1.4986)
			(layers "F.Cu" "F.Mask" "F.Paste")
			(net "Net_2385")
		)
		(pad "151" smd rect
			(at 2.050034 -58.224928 90)
			(size 0.519938 1.4986)
			(layers "F.Cu" "F.Mask" "F.Paste")
			(net "GND")
		)
		(pad "152" smd rect
			(at 2.050034 -57.375044 90)
			(size 0.519938 1.4986)
			(layers "F.Cu" "F.Mask" "F.Paste")
			(net "M_J_CPU1_SA_DQ<2>")
		)
		(pad "153" smd rect
			(at 2.050034 -56.524906 90)
			(size 0.519938 1.4986)
			(layers "F.Cu" "F.Mask" "F.Paste")
			(net "GND")
		)
		(pad "154" smd rect
			(at 2.050034 -55.675022 90)
			(size 0.519938 1.4986)
			(layers "F.Cu" "F.Mask" "F.Paste")
			(net "M_J_CPU1_SA_DQ<3>")
		)
		(pad "155" smd rect
			(at 2.050034 -54.824884 90)
			(size 0.519938 1.4986)
			(layers "F.Cu" "F.Mask" "F.Paste")
			(net "GND")
		)
		(pad "156" smd rect
			(at 2.050034 -53.975 90)
			(size 0.519938 1.4986)
			(layers "F.Cu" "F.Mask" "F.Paste")
			(net "M_J_CPU1_SA_DQS_DN<5>")
		)
		(pad "157" smd rect
			(at 2.050034 -53.125116 90)
			(size 0.519938 1.4986)
			(layers "F.Cu" "F.Mask" "F.Paste")
			(net "M_J_CPU1_SA_DQS_DP<5>")
		)
		(pad "158" smd rect
			(at 2.050034 -52.274978 90)
			(size 0.519938 1.4986)
			(layers "F.Cu" "F.Mask" "F.Paste")
			(net "GND")
		)
		(pad "159" smd rect
			(at 2.050034 -51.425094 90)
			(size 0.519938 1.4986)
			(layers "F.Cu" "F.Mask" "F.Paste")
			(net "M_J_CPU1_SA_DQ<6>")
		)
		(pad "160" smd rect
			(at 2.050034 -50.574956 90)
			(size 0.519938 1.4986)
			(layers "F.Cu" "F.Mask" "F.Paste")
			(net "GND")
		)
		(pad "161" smd rect
			(at 2.050034 -49.725072 90)
			(size 0.519938 1.4986)
			(layers "F.Cu" "F.Mask" "F.Paste")
			(net "M_J_CPU1_SA_DQ<7>")
		)
		(pad "162" smd rect
			(at 2.050034 -48.874934 90)
			(size 0.519938 1.4986)
			(layers "F.Cu" "F.Mask" "F.Paste")
			(net "GND")
		)
		(pad "163" smd rect
			(at 2.050034 -48.02505 90)
			(size 0.519938 1.4986)
			(layers "F.Cu" "F.Mask" "F.Paste")
			(net "M_J_CPU1_SA_DQ<10>")
		)
		(pad "164" smd rect
			(at 2.050034 -47.174912 90)
			(size 0.519938 1.4986)
			(layers "F.Cu" "F.Mask" "F.Paste")
			(net "GND")
		)
		(pad "165" smd rect
			(at 2.050034 -46.325028 90)
			(size 0.519938 1.4986)
			(layers "F.Cu" "F.Mask" "F.Paste")
			(net "M_J_CPU1_SA_DQ<11>")
		)
		(pad "166" smd rect
			(at 2.050034 -45.47489 90)
			(size 0.519938 1.4986)
			(layers "F.Cu" "F.Mask" "F.Paste")
			(net "GND")
		)
		(pad "167" smd rect
			(at 2.050034 -44.625006 90)
			(size 0.519938 1.4986)
			(layers "F.Cu" "F.Mask" "F.Paste")
			(net "M_J_CPU1_SA_DQS_DN<6>")
		)
		(pad "168" smd rect
			(at 2.050034 -43.775122 90)
			(size 0.519938 1.4986)
			(layers "F.Cu" "F.Mask" "F.Paste")
			(net "M_J_CPU1_SA_DQS_DP<6>")
		)
		(pad "169" smd rect
			(at 2.050034 -42.924984 90)
			(size 0.519938 1.4986)
			(layers "F.Cu" "F.Mask" "F.Paste")
			(net "GND")
		)
		(pad "170" smd rect
			(at 2.050034 -42.0751 90)
			(size 0.519938 1.4986)
			(layers "F.Cu" "F.Mask" "F.Paste")
			(net "M_J_CPU1_SA_DQ<14>")
		)
		(pad "171" smd rect
			(at 2.050034 -41.224962 90)
			(size 0.519938 1.4986)
			(layers "F.Cu" "F.Mask" "F.Paste")
			(net "GND")
		)
		(pad "172" smd rect
			(at 2.050034 -40.375078 90)
			(size 0.519938 1.4986)
			(layers "F.Cu" "F.Mask" "F.Paste")
			(net "M_J_CPU1_SA_DQ<15>")
		)
		(pad "173" smd rect
			(at 2.050034 -39.52494 90)
			(size 0.519938 1.4986)
			(layers "F.Cu" "F.Mask" "F.Paste")
			(net "GND")
		)
		(pad "174" smd rect
			(at 2.050034 -38.675056 90)
			(size 0.519938 1.4986)
			(layers "F.Cu" "F.Mask" "F.Paste")
			(net "M_J_CPU1_SA_DQ<18>")
		)
		(pad "175" smd rect
			(at 2.050034 -37.824918 90)
			(size 0.519938 1.4986)
			(layers "F.Cu" "F.Mask" "F.Paste")
			(net "GND")
		)
		(pad "176" smd rect
			(at 2.050034 -36.975034 90)
			(size 0.519938 1.4986)
			(layers "F.Cu" "F.Mask" "F.Paste")
			(net "M_J_CPU1_SA_DQ<19>")
		)
		(pad "177" smd rect
			(at 2.050034 -36.124896 90)
			(size 0.519938 1.4986)
			(layers "F.Cu" "F.Mask" "F.Paste")
			(net "GND")
		)
		(pad "178" smd rect
			(at 2.050034 -35.275012 90)
			(size 0.519938 1.4986)
			(layers "F.Cu" "F.Mask" "F.Paste")
			(net "M_J_CPU1_SA_DQS_DN<7>")
		)
		(pad "179" smd rect
			(at 2.050034 -34.425128 90)
			(size 0.519938 1.4986)
			(layers "F.Cu" "F.Mask" "F.Paste")
			(net "M_J_CPU1_SA_DQS_DP<7>")
		)
		(pad "180" smd rect
			(at 2.050034 -33.57499 90)
			(size 0.519938 1.4986)
			(layers "F.Cu" "F.Mask" "F.Paste")
			(net "GND")
		)
		(pad "181" smd rect
			(at 2.050034 -32.725106 90)
			(size 0.519938 1.4986)
			(layers "F.Cu" "F.Mask" "F.Paste")
			(net "M_J_CPU1_SA_DQ<22>")
		)
		(pad "182" smd rect
			(at 2.050034 -31.874968 90)
			(size 0.519938 1.4986)
			(layers "F.Cu" "F.Mask" "F.Paste")
			(net "GND")
		)
		(pad "183" smd rect
			(at 2.050034 -31.025084 90)
			(size 0.519938 1.4986)
			(layers "F.Cu" "F.Mask" "F.Paste")
			(net "M_J_CPU1_SA_DQ<23>")
		)
		(pad "184" smd rect
			(at 2.050034 -30.174946 90)
			(size 0.519938 1.4986)
			(layers "F.Cu" "F.Mask" "F.Paste")
			(net "GND")
		)
		(pad "185" smd rect
			(at 2.050034 -29.325062 90)
			(size 0.519938 1.4986)
			(layers "F.Cu" "F.Mask" "F.Paste")
			(net "M_J_CPU1_SA_DQ<26>")
		)
		(pad "186" smd rect
			(at 2.050034 -28.474924 90)
			(size 0.519938 1.4986)
			(layers "F.Cu" "F.Mask" "F.Paste")
			(net "GND")
		)
		(pad "187" smd rect
			(at 2.050034 -27.62504 90)
			(size 0.519938 1.4986)
			(layers "F.Cu" "F.Mask" "F.Paste")
			(net "M_J_CPU1_SA_DQ<27>")
		)
		(pad "188" smd rect
			(at 2.050034 -26.774902 90)
			(size 0.519938 1.4986)
			(layers "F.Cu" "F.Mask" "F.Paste")
			(net "GND")
		)
		(pad "189" smd rect
			(at 2.050034 -25.925018 90)
			(size 0.519938 1.4986)
			(layers "F.Cu" "F.Mask" "F.Paste")
			(net "M_J_CPU1_SA_DQS_DN<8>")
		)
		(pad "190" smd rect
			(at 2.050034 -25.07488 90)
			(size 0.519938 1.4986)
			(layers "F.Cu" "F.Mask" "F.Paste")
			(net "M_J_CPU1_SA_DQS_DP<8>")
		)
		(pad "191" smd rect
			(at 2.050034 -24.224996 90)
			(size 0.519938 1.4986)
			(layers "F.Cu" "F.Mask" "F.Paste")
			(net "GND")
		)
		(pad "192" smd rect
			(at 2.050034 -23.375112 90)
			(size 0.519938 1.4986)
			(layers "F.Cu" "F.Mask" "F.Paste")
			(net "M_J_CPU1_SA_DQ<30>")
		)
		(pad "193" smd rect
			(at 2.050034 -22.524974 90)
			(size 0.519938 1.4986)
			(layers "F.Cu" "F.Mask" "F.Paste")
			(net "GND")
		)
		(pad "194" smd rect
			(at 2.050034 -21.67509 90)
			(size 0.519938 1.4986)
			(layers "F.Cu" "F.Mask" "F.Paste")
			(net "M_J_CPU1_SA_DQ<31>")
		)
		(pad "195" smd rect
			(at 2.050034 -20.824952 90)
			(size 0.519938 1.4986)
			(layers "F.Cu" "F.Mask" "F.Paste")
			(net "GND")
		)
		(pad "196" smd rect
			(at 2.050034 -19.975068 90)
			(size 0.519938 1.4986)
			(layers "F.Cu" "F.Mask" "F.Paste")
			(net "M_J_CPU1_SA_CB<2>")
		)
		(pad "197" smd rect
			(at 2.050034 -19.12493 90)
			(size 0.519938 1.4986)
			(layers "F.Cu" "F.Mask" "F.Paste")
			(net "GND")
		)
		(pad "198" smd rect
			(at 2.050034 -18.275046 90)
			(size 0.519938 1.4986)
			(layers "F.Cu" "F.Mask" "F.Paste")
			(net "M_J_CPU1_SA_CB<3>")
		)
		(pad "199" smd rect
			(at 2.050034 -17.424908 90)
			(size 0.519938 1.4986)
			(layers "F.Cu" "F.Mask" "F.Paste")
			(net "GND")
		)
		(pad "200" smd rect
			(at 2.050034 -16.575024 90)
			(size 0.519938 1.4986)
			(layers "F.Cu" "F.Mask" "F.Paste")
			(net "M_J_CPU1_SA_DQS_DN<9>")
		)
		(pad "201" smd rect
			(at 2.050034 -15.724886 90)
			(size 0.519938 1.4986)
			(layers "F.Cu" "F.Mask" "F.Paste")
			(net "M_J_CPU1_SA_DQS_DP<9>")
		)
		(pad "202" smd rect
			(at 2.050034 -14.875002 90)
			(size 0.519938 1.4986)
			(layers "F.Cu" "F.Mask" "F.Paste")
			(net "GND")
		)
		(pad "203" smd rect
			(at 2.050034 -14.025118 90)
			(size 0.519938 1.4986)
			(layers "F.Cu" "F.Mask" "F.Paste")
			(net "M_J_CPU1_SA_CB<6>")
		)
		(pad "204" smd rect
			(at 2.050034 -13.17498 90)
			(size 0.519938 1.4986)
			(layers "F.Cu" "F.Mask" "F.Paste")
			(net "GND")
		)
		(pad "205" smd rect
			(at 2.050034 -12.325096 90)
			(size 0.519938 1.4986)
			(layers "F.Cu" "F.Mask" "F.Paste")
			(net "M_J_CPU1_SA_CB<7>")
		)
		(pad "206" smd rect
			(at 2.050034 -11.474958 90)
			(size 0.519938 1.4986)
			(layers "F.Cu" "F.Mask" "F.Paste")
			(net "GND")
		)
		(pad "207" smd rect
			(at 2.050034 -10.625074 90)
			(size 0.519938 1.4986)
			(layers "F.Cu" "F.Mask" "F.Paste")
			(net "M_J_CPU1_RESET_N")
		)
		(pad "208" smd rect
			(at 2.050034 -9.774936 90)
			(size 0.519938 1.4986)
			(layers "F.Cu" "F.Mask" "F.Paste")
			(net "GND")
		)
		(pad "209" smd rect
			(at 2.050034 -8.925052 90)
			(size 0.519938 1.4986)
			(layers "F.Cu" "F.Mask" "F.Paste")
			(net "M_J_CPU1_SA_CS_N<1>")
		)
		(pad "210" smd rect
			(at 2.050034 -8.074914 90)
			(size 0.519938 1.4986)
			(layers "F.Cu" "F.Mask" "F.Paste")
			(net "GND")
		)
		(pad "211" smd rect
			(at 2.050034 -7.22503 90)
			(size 0.519938 1.4986)
			(layers "F.Cu" "F.Mask" "F.Paste")
			(net "M_J_CPU1_SA_CA<1>")
		)
		(pad "212" smd rect
			(at 2.050034 -6.374892 90)
			(size 0.519938 1.4986)
			(layers "F.Cu" "F.Mask" "F.Paste")
			(net "GND")
		)
		(pad "213" smd rect
			(at 2.050034 -5.525008 90)
			(size 0.519938 1.4986)
			(layers "F.Cu" "F.Mask" "F.Paste")
			(net "M_J_CPU1_SA_CA<3>")
		)
		(pad "214" smd rect
			(at 2.050034 -4.675124 90)
			(size 0.519938 1.4986)
			(layers "F.Cu" "F.Mask" "F.Paste")
			(net "GND")
		)
		(pad "215" smd rect
			(at 2.050034 -3.824986 90)
			(size 0.519938 1.4986)
			(layers "F.Cu" "F.Mask" "F.Paste")
			(net "M_J_CPU1_SA_CA<5>")
		)
		(pad "216" smd rect
			(at 2.050034 -2.975102 90)
			(size 0.519938 1.4986)
			(layers "F.Cu" "F.Mask" "F.Paste")
			(net "GND")
		)
		(pad "217" smd rect
			(at 2.050034 -2.124964 90)
			(size 0.519938 1.4986)
			(layers "F.Cu" "F.Mask" "F.Paste")
			(net "M_J_CPU1_CLK_DP<0>")
		)
		(pad "218" smd rect
			(at 2.050034 -1.27508 90)
			(size 0.519938 1.4986)
			(layers "F.Cu" "F.Mask" "F.Paste")
			(net "M_J_CPU1_CLK_DN<0>")
		)
		(pad "219" smd rect
			(at 2.050034 -0.424942 90)
			(size 0.519938 1.4986)
			(layers "F.Cu" "F.Mask" "F.Paste")
			(net "GND")
		)
		(pad "220" smd rect
			(at 2.050034 5.525008 90)
			(size 0.519938 1.4986)
			(layers "F.Cu" "F.Mask" "F.Paste")
			(net "Net_2386")
		)
		(pad "221" smd rect
			(at 2.050034 6.374892 90)
			(size 0.519938 1.4986)
			(layers "F.Cu" "F.Mask" "F.Paste")
			(net "M_J_CPU1_SB_CA<1>")
		)
		(pad "222" smd rect
			(at 2.050034 7.22503 90)
			(size 0.519938 1.4986)
			(layers "F.Cu" "F.Mask" "F.Paste")
			(net "GND")
		)
		(pad "223" smd rect
			(at 2.050034 8.074914 90)
			(size 0.519938 1.4986)
			(layers "F.Cu" "F.Mask" "F.Paste")
			(net "M_J_CPU1_SB_CA<3>")
		)
		(pad "224" smd rect
			(at 2.050034 8.925052 90)
			(size 0.519938 1.4986)
			(layers "F.Cu" "F.Mask" "F.Paste")
			(net "GND")
		)
		(pad "225" smd rect
			(at 2.050034 9.774936 90)
			(size 0.519938 1.4986)
			(layers "F.Cu" "F.Mask" "F.Paste")
			(net "M_J_CPU1_SB_CA<5>")
		)
		(pad "226" smd rect
			(at 2.050034 10.625074 90)
			(size 0.519938 1.4986)
			(layers "F.Cu" "F.Mask" "F.Paste")
			(net "GND")
		)
	)
)
